# T6G (Grand Teton) — schematic netlist excerpt (pin names and nets, part order shuffled) for the footprints in the layout excerpt that follows; sources: Cadence DE-HDL packaged netlist, KiCad conversion of 04192023_DAF0TMB3IC0_F0TG_MB_C_brd_V02_OCP.brd

X9028  TP_TDR_4P_FTS  TP_TDR_4P_DIP EMPTY  pkg TH  page 261
  S1  = TDR_DIFF_85_NECK_IN6_DN
  P1  = T1_GND
  P2  = T1_GND
  S2  = TDR_DIFF_85_NECK_IN6_DP

R4120  Q_RES  100K 1% EMPTY  pkg 0402LF  page 125 : A = GPU_3V3IO_RSVD0_FFU ; B = GND

(kicad_pcb
	(version 20260206)
	(generator "pcbnew")
	(generator_version "10.0")
	(general
		(thickness 1.6)
		(legacy_teardrops no)
	)
	(paper "A4")
	(title_block
		(title "04192023_DAF0TMB3IC0_F0TG_MB_C_brd_V02_OCP.brd")
		(comment 1 "Grand Teton / footprints 8066-8067 of 8354")
	)
	(layers
		(0 "F.Cu" signal "TOP")
		(4 "In1.Cu" signal "GND")
		(6 "In2.Cu" signal "IN1")
		(8 "In3.Cu" signal "GND1")
		(10 "In4.Cu" signal "IN2")
		(12 "In5.Cu" signal "GND2")
		(14 "In6.Cu" signal "IN3")
		(16 "In7.Cu" signal "GND3")
		(18 "In8.Cu" signal "VCC")
		(20 "In9.Cu" signal "VCC1")
		(22 "In10.Cu" signal "GND4")
		(24 "In11.Cu" signal "IN4")
		(26 "In12.Cu" signal "GND5")
		(28 "In13.Cu" signal "IN5")
		(30 "In14.Cu" signal "GND6")
		(32 "In15.Cu" signal "IN6")
		(34 "In16.Cu" signal "GND7")
		(2 "B.Cu" signal "BOTTOM")
		(9 "F.Adhes" user "F.Adhesive")
		(11 "B.Adhes" user "B.Adhesive")
		(13 "F.Paste" user "Package Geometry/Pastemask Top")
		(15 "B.Paste" user "Package Geometry/Pastemask Bottom")
		(5 "F.SilkS" user "Ref Des/Silkscreen Top")
		(7 "B.SilkS" user "Ref Des/Silkscreen Bottom")
		(1 "F.Mask" user "Board Geometry/Soldermask Top")
		(3 "B.Mask" user "Board Geometry/Soldermask Bottom")
		(17 "Dwgs.User" user "User.Drawings")
		(19 "Cmts.User" user "User.Comments")
		(21 "Eco1.User" user "User.Eco1")
		(23 "Eco2.User" user "User.Eco2")
		(25 "Edge.Cuts" user "Board Geometry/Outline")
		(27 "Margin" user)
		(31 "F.CrtYd" user "Package Geometry/Place Bound Top")
		(29 "B.CrtYd" user "Package Geometry/Place Bound Bottom")
		(35 "F.Fab" user "Ref Des/Assembly Top")
		(33 "B.Fab" user "Ref Des/Assembly Bottom")
	)
	(footprint ""
		(layer "B.Cu")
		(at 487.620564 -306.87264 90)
		(property "Reference" "X9028"
			(at 4.62026 -1.55829 90)
			(unlocked yes)
			(layer "B.SilkS")
			(effects
				(font
					(size 0.7874 0.5842)
					(thickness 0.1524)
				)
				(justify left mirror)
			)
		)
		(property "Value" ""
			(at 0 0 90)
			(layer "B.Fab")
			(effects
				(font
					(size 1.27 1.27)
				)
				(justify mirror)
			)
		)
		(property "User Part Number" "N_A"
			(at -1.30175 1.27 0)
			(unlocked yes)
			(layer "Cmts.User")
			(hide yes)
			(effects
				(font
					(size 0.635 0.4064)
					(thickness 0.1524)
				)
				(justify mirror)
			)
		)
		(property "Device Type" "TP_TDR_4P_FTS_TH-TP_TDR_4P_DIP,EMPTY,TP15"
			(at -1.30175 1.27 0)
			(unlocked yes)
			(layer "B.Fab")
			(hide yes)
			(effects
				(font
					(size 0.635 0.4064)
					(thickness 0.1524)
				)
				(justify mirror)
			)
		)
		(duplicate_pad_numbers_are_jumpers no)
		(fp_line
			(start 0 -1.27)
			(end 0 -0.635)
			(stroke
				(width 0.1524)
				(type default)
			)
			(layer "B.SilkS")
		)
		(fp_line
			(start -2.54 -1.27)
			(end 0 -1.27)
			(stroke
				(width 0.1524)
				(type default)
			)
			(layer "B.SilkS")
		)
		(fp_line
			(start -2.54 -1.1303)
			(end -2.54 -1.27)
			(stroke
				(width 0.1524)
				(type default)
			)
			(layer "B.SilkS")
		)
		(fp_line
			(start 0 0.635)
			(end 0 1.905)
			(stroke
				(width 0.1524)
				(type default)
			)
			(layer "B.SilkS")
		)
		(fp_line
			(start -2.54 1.4097)
			(end -2.54 1.1303)
			(stroke
				(width 0.1524)
				(type default)
			)
			(layer "B.SilkS")
		)
		(fp_line
			(start 0 3.175)
			(end 0 3.81)
			(stroke
				(width 0.1524)
				(type default)
			)
			(layer "B.SilkS")
		)
		(fp_line
			(start 0 3.81)
			(end -2.54 3.81)
			(stroke
				(width 0.1524)
				(type default)
			)
			(layer "B.SilkS")
		)
		(fp_line
			(start -2.54 3.81)
			(end -2.54 3.6703)
			(stroke
				(width 0.1524)
				(type default)
			)
			(layer "B.SilkS")
		)
		(fp_poly
			(pts
				(xy 0.761746 0) (xy 2.285746 -0.762) (xy 2.285746 0.762)
			)
			(stroke
				(width 0)
				(type default)
			)
			(fill yes)
			(layer "B.SilkS")
		)
		(fp_line
			(start 0 -1.27)
			(end 0 3.81)
			(stroke
				(width 0.1)
				(type default)
			)
			(layer "B.Fab")
		)
		(fp_line
			(start -2.54 -1.27)
			(end 0 -1.27)
			(stroke
				(width 0.1)
				(type default)
			)
			(layer "B.Fab")
		)
		(fp_line
			(start 0 3.81)
			(end -2.54 3.81)
			(stroke
				(width 0.1)
				(type default)
			)
			(layer "B.Fab")
		)
		(fp_line
			(start -2.54 3.81)
			(end -2.54 -1.27)
			(stroke
				(width 0.1)
				(type default)
			)
			(layer "B.Fab")
		)
		(fp_poly
			(pts
				(xy 0.761746 0) (xy 2.285746 -0.762) (xy 2.285746 0.762)
			)
			(stroke
				(width 0)
				(type default)
			)
			(fill yes)
			(layer "B.Fab")
		)
		(pad "1" thru_hole circle
			(at 0 0 270)
			(size 1.0033 1.0033)
			(drill 0.249936)
			(layers "*.Cu" "*.Mask")
			(remove_unused_layers no)
			(net "TDR_DIFF_85_NECK_IN6_DN")
			(clearance 0.10795)
			(padstack
				(mode front_inner_back)
				(layer "Inner"
					(shape circle)
					(size 0.8001 0.8001)
					(clearance 0.1524)
				)
				(layer "B.Cu"
					(shape circle)
					(size 1.0033 1.0033)
					(thermal_gap 0.10795)
					(clearance 0.10795)
				)
			)
		)
		(pad "2" thru_hole circle
			(at -2.54 0 270)
			(size 1.9939 1.9939)
			(drill 0.249936)
			(layers "*.Cu" "*.Mask")
			(remove_unused_layers no)
			(net "T1_GND")
			(clearance 0.10795)
			(padstack
				(mode front_inner_back)
				(layer "Inner"
					(shape circle)
					(size 0.8001 0.8001)
					(clearance 0.1524)
				)
				(layer "B.Cu"
					(shape circle)
					(size 1.9939 1.9939)
					(thermal_gap 0.10795)
					(clearance 0.10795)
				)
			)
		)
		(pad "3" thru_hole circle
			(at -2.54 2.54 270)
			(size 1.9939 1.9939)
			(drill 0.249936)
			(layers "*.Cu" "*.Mask")
			(remove_unused_layers no)
			(net "T1_GND")
			(clearance 0.10795)
			(padstack
				(mode front_inner_back)
				(layer "Inner"
					(shape circle)
					(size 0.8001 0.8001)
					(clearance 0.1524)
				)
				(layer "B.Cu"
					(shape circle)
					(size 1.9939 1.9939)
					(thermal_gap 0.10795)
					(clearance 0.10795)
				)
			)
		)
		(pad "4" thru_hole circle
			(at 0 2.54 270)
			(size 1.0033 1.0033)
			(drill 0.249936)
			(layers "*.Cu" "*.Mask")
			(remove_unused_layers no)
			(net "TDR_DIFF_85_NECK_IN6_DP")
			(clearance 0.10795)
			(padstack
				(mode front_inner_back)
				(layer "Inner"
					(shape circle)
					(size 0.8001 0.8001)
					(clearance 0.1524)
				)
				(layer "B.Cu"
					(shape circle)
					(size 1.0033 1.0033)
					(thermal_gap 0.10795)
					(clearance 0.10795)
				)
			)
		)
	)
	(footprint ""
		(layer "B.Cu")
		(at 165.599618 -417.962588)
		(property "Reference" "R4120"
			(at 0 0 0)
			(layer "B.SilkS")
			(hide yes)
			(effects
				(font
					(size 1.27 1.27)
				)
				(justify mirror)
			)
		)
		(property "Value" ""
			(at 0 0 0)
			(layer "B.Fab")
			(effects
				(font
					(size 1.27 1.27)
				)
				(justify mirror)
			)
		)
		(duplicate_pad_numbers_are_jumpers no)
		(fp_line
			(start -0.7874 -0.4064)
			(end -0.7874 0.4064)
			(stroke
				(width 0.1524)
				(type default)
			)
			(layer "B.SilkS")
		)
		(fp_line
			(start -0.7874 0.4064)
			(end 0.7874 0.4064)
			(stroke
				(width 0.1524)
				(type default)
			)
			(layer "B.SilkS")
		)
		(fp_line
			(start 0.7874 -0.4064)
			(end -0.7874 -0.4064)
			(stroke
				(width 0.1524)
				(type default)
			)
			(layer "B.SilkS")
		)
		(fp_line
			(start 0.7874 0.4064)
			(end 0.7874 -0.4064)
			(stroke
				(width 0.1524)
				(type default)
			)
			(layer "B.SilkS")
		)
		(fp_line
			(start -0.67945 -0.3048)
			(end -0.67945 0.3048)
			(stroke
				(width 0.1)
				(type default)
			)
			(layer "B.Fab")
		)
		(fp_line
			(start -0.67945 0.3048)
			(end -0.120396 0.3048)
			(stroke
				(width 0.1)
				(type default)
			)
			(layer "B.Fab")
		)
		(fp_line
			(start -0.12065 -0.3048)
			(end -0.67945 -0.3048)
			(stroke
				(width 0.1)
				(type default)
			)
			(layer "B.Fab")
		)
		(fp_line
			(start -0.12065 -0.2794)
			(end -0.12065 -0.3048)
			(stroke
				(width 0.1)
				(type default)
			)
			(layer "B.Fab")
		)
		(fp_line
			(start -0.120396 0.2794)
			(end 0.12065 0.2794)
			(stroke
				(width 0.1)
				(type default)
			)
			(layer "B.Fab")
		)
		(fp_line
			(start -0.120396 0.3048)
			(end -0.120396 0.2794)
			(stroke
				(width 0.1)
				(type default)
			)
			(layer "B.Fab")
		)
		(fp_line
			(start 0.12065 -0.305054)
			(end 0.12065 -0.2794)
			(stroke
				(width 0.1)
				(type default)
			)
			(layer "B.Fab")
		)
		(fp_line
			(start 0.12065 -0.2794)
			(end -0.12065 -0.2794)
			(stroke
				(width 0.1)
				(type default)
			)
			(layer "B.Fab")
		)
		(fp_line
			(start 0.12065 0.2794)
			(end 0.12065 0.3048)
			(stroke
				(width 0.1)
				(type default)
			)
			(layer "B.Fab")
		)
		(fp_line
			(start 0.12065 0.3048)
			(end 0.67945 0.3048)
			(stroke
				(width 0.1)
				(type default)
			)
			(layer "B.Fab")
		)
		(fp_line
			(start 0.67945 -0.305054)
			(end 0.12065 -0.305054)
			(stroke
				(width 0.1)
				(type default)
			)
			(layer "B.Fab")
		)
		(fp_line
			(start 0.67945 0.3048)
			(end 0.67945 -0.305054)
			(stroke
				(width 0.1)
				(type default)
			)
			(layer "B.Fab")
		)
		(pad "1" smd circle
			(at 0.40005 0 180)
			(size 0 0)
			(layers "B.Cu" "B.Mask" "B.Paste")
			(net "GPU_3V3IO_RSVD0_FFU")
		)
		(pad "2" smd circle
			(at -0.40005 0 180)
			(size 0 0)
			(layers "B.Cu" "B.Mask" "B.Paste")
			(net "GND")
		)
	)
)
